(kicad_pcb
	(version 20260206)
	(generator "pcbnew")
	(generator_version "10.0")
	(general
		(thickness 1.6)
		(legacy_teardrops no)
	)
	(paper "A4")
	(title_block
		(title "01162023_DA0F0TEBIF0_F0T_Expander_BD_F_brd_V02_OCP.brd")
		(comment 1 "Grand Teton / footprints 9569-9576 of 9728")
	)
	(layers
		(0 "F.Cu" signal "TOP")
		(4 "In1.Cu" signal "GND")
		(6 "In2.Cu" signal "VCC")
		(8 "In3.Cu" signal "VCC1")
		(10 "In4.Cu" signal "GND1")
		(12 "In5.Cu" signal "IN1")
		(14 "In6.Cu" signal "GND2")
		(16 "In7.Cu" signal "IN2")
		(18 "In8.Cu" signal "GND3")
		(20 "In9.Cu" signal "IN3")
		(22 "In10.Cu" signal "GND4")
		(24 "In11.Cu" signal "IN4")
		(26 "In12.Cu" signal "GND5")
		(28 "In13.Cu" signal "IN5")
		(30 "In14.Cu" signal "GND6")
		(32 "In15.Cu" signal "IN6")
		(34 "In16.Cu" signal "GND7")
		(2 "B.Cu" signal "BOTTOM")
		(9 "F.Adhes" user "F.Adhesive")
		(11 "B.Adhes" user "B.Adhesive")
		(13 "F.Paste" user "Package Geometry/Pastemask Top")
		(15 "B.Paste" user "Package Geometry/Pastemask Bottom")
		(5 "F.SilkS" user "Ref Des/Silkscreen Top")
		(7 "B.SilkS" user "Ref Des/Silkscreen Bottom")
		(1 "F.Mask" user "Board Geometry/Soldermask Top")
		(3 "B.Mask" user "Board Geometry/Soldermask Bottom")
		(17 "Dwgs.User" user "User.Drawings")
		(19 "Cmts.User" user "User.Comments")
		(21 "Eco1.User" user "User.Eco1")
		(23 "Eco2.User" user "User.Eco2")
		(25 "Edge.Cuts" user "Board Geometry/Outline")
		(27 "Margin" user)
		(31 "F.CrtYd" user "Package Geometry/Place Bound Top")
		(29 "B.CrtYd" user "Package Geometry/Place Bound Bottom")
		(35 "F.Fab" user "Ref Des/Assembly Top")
		(33 "B.Fab" user "Ref Des/Assembly Bottom")
	)
	(footprint ""
		(layer "B.Cu")
		(at 399.445734 -296.37482)
		(property "Reference" "C1874"
			(at 0 0 0)
			(layer "B.SilkS")
			(hide yes)
			(effects
				(font
					(size 1.27 1.27)
				)
				(justify mirror)
			)
		)
		(property "Value" ""
			(at 0 0 0)
			(layer "B.Fab")
			(effects
				(font
					(size 1.27 1.27)
				)
				(justify mirror)
			)
		)
		(duplicate_pad_numbers_are_jumpers no)
		(fp_line
			(start -0.299974 -0.150114)
			(end -0.299974 0.150114)
			(stroke
				(width 0.1)
				(type default)
			)
			(layer "B.Fab")
		)
		(fp_line
			(start -0.299974 0.150114)
			(end 0.299974 0.150114)
			(stroke
				(width 0.1)
				(type default)
			)
			(layer "B.Fab")
		)
		(fp_line
			(start 0.299974 -0.150114)
			(end -0.299974 -0.150114)
			(stroke
				(width 0.1)
				(type default)
			)
			(layer "B.Fab")
		)
		(fp_line
			(start 0.299974 0.150114)
			(end 0.299974 -0.150114)
			(stroke
				(width 0.1)
				(type default)
			)
			(layer "B.Fab")
		)
		(pad "1" smd rect
			(at 0.2667 0 180)
			(size 0.3048 0.381)
			(layers "B.Cu" "B.Mask" "B.Paste")
			(net "P0V8_PEX3")
		)
		(pad "2" smd rect
			(at -0.2667 0 180)
			(size 0.3048 0.381)
			(layers "B.Cu" "B.Mask" "B.Paste")
			(net "GND")
		)
	)
	(footprint ""
		(layer "B.Cu")
		(at 172.106844 -136.652 -90)
		(property "Reference" "R138"
			(at 0 0 90)
			(layer "B.SilkS")
			(hide yes)
			(effects
				(font
					(size 1.27 1.27)
				)
				(justify mirror)
			)
		)
		(property "Value" ""
			(at 0 0 90)
			(layer "B.Fab")
			(effects
				(font
					(size 1.27 1.27)
				)
				(justify mirror)
			)
		)
		(duplicate_pad_numbers_are_jumpers no)
		(fp_line
			(start -0.7874 0.4064)
			(end 0.7874 0.4064)
			(stroke
				(width 0.1524)
				(type default)
			)
			(layer "B.SilkS")
		)
		(fp_line
			(start 0.7874 0.4064)
			(end 0.7874 -0.4064)
			(stroke
				(width 0.1524)
				(type default)
			)
			(layer "B.SilkS")
		)
		(fp_line
			(start -0.7874 -0.4064)
			(end -0.7874 0.4064)
			(stroke
				(width 0.1524)
				(type default)
			)
			(layer "B.SilkS")
		)
		(fp_line
			(start 0.7874 -0.4064)
			(end -0.7874 -0.4064)
			(stroke
				(width 0.1524)
				(type default)
			)
			(layer "B.SilkS")
		)
		(fp_line
			(start -0.67945 0.3048)
			(end -0.120396 0.3048)
			(stroke
				(width 0.1)
				(type default)
			)
			(layer "B.Fab")
		)
		(fp_line
			(start -0.120396 0.3048)
			(end -0.120396 0.2794)
			(stroke
				(width 0.1)
				(type default)
			)
			(layer "B.Fab")
		)
		(fp_line
			(start 0.12065 0.3048)
			(end 0.67945 0.3048)
			(stroke
				(width 0.1)
				(type default)
			)
			(layer "B.Fab")
		)
		(fp_line
			(start 0.67945 0.3048)
			(end 0.67945 -0.305054)
			(stroke
				(width 0.1)
				(type default)
			)
			(layer "B.Fab")
		)
		(fp_line
			(start -0.120396 0.2794)
			(end 0.12065 0.2794)
			(stroke
				(width 0.1)
				(type default)
			)
			(layer "B.Fab")
		)
		(fp_line
			(start 0.12065 0.2794)
			(end 0.12065 0.3048)
			(stroke
				(width 0.1)
				(type default)
			)
			(layer "B.Fab")
		)
		(fp_line
			(start -0.12065 -0.2794)
			(end -0.12065 -0.3048)
			(stroke
				(width 0.1)
				(type default)
			)
			(layer "B.Fab")
		)
		(fp_line
			(start 0.12065 -0.2794)
			(end -0.12065 -0.2794)
			(stroke
				(width 0.1)
				(type default)
			)
			(layer "B.Fab")
		)
		(fp_line
			(start -0.67945 -0.3048)
			(end -0.67945 0.3048)
			(stroke
				(width 0.1)
				(type default)
			)
			(layer "B.Fab")
		)
		(fp_line
			(start -0.12065 -0.3048)
			(end -0.67945 -0.3048)
			(stroke
				(width 0.1)
				(type default)
			)
			(layer "B.Fab")
		)
		(fp_line
			(start 0.12065 -0.305054)
			(end 0.12065 -0.2794)
			(stroke
				(width 0.1)
				(type default)
			)
			(layer "B.Fab")
		)
		(fp_line
			(start 0.67945 -0.305054)
			(end 0.12065 -0.305054)
			(stroke
				(width 0.1)
				(type default)
			)
			(layer "B.Fab")
		)
		(pad "1" smd circle
			(at 0.40005 0 90)
			(size 0 0)
			(layers "B.Cu" "B.Mask" "B.Paste")
			(net "RST_SMB_NIC_MUX_R_N")
		)
		(pad "2" smd circle
			(at -0.40005 0 90)
			(size 0 0)
			(layers "B.Cu" "B.Mask" "B.Paste")
			(net "RST_SMB_NIC2_MUX_N")
		)
	)
	(footprint ""
		(layer "B.Cu")
		(at 301.349918 -296.37482 180)
		(property "Reference" "C1676"
			(at 0 0 0)
			(layer "B.SilkS")
			(hide yes)
			(effects
				(font
					(size 1.27 1.27)
				)
				(justify mirror)
			)
		)
		(property "Value" ""
			(at 0 0 0)
			(layer "B.Fab")
			(effects
				(font
					(size 1.27 1.27)
				)
				(justify mirror)
			)
		)
		(duplicate_pad_numbers_are_jumpers no)
		(fp_line
			(start 0.299974 0.150114)
			(end 0.299974 -0.150114)
			(stroke
				(width 0.1)
				(type default)
			)
			(layer "B.Fab")
		)
		(fp_line
			(start 0.299974 -0.150114)
			(end -0.299974 -0.150114)
			(stroke
				(width 0.1)
				(type default)
			)
			(layer "B.Fab")
		)
		(fp_line
			(start -0.299974 0.150114)
			(end 0.299974 0.150114)
			(stroke
				(width 0.1)
				(type default)
			)
			(layer "B.Fab")
		)
		(fp_line
			(start -0.299974 -0.150114)
			(end -0.299974 0.150114)
			(stroke
				(width 0.1)
				(type default)
			)
			(layer "B.Fab")
		)
		(pad "1" smd rect
			(at 0.2667 0)
			(size 0.3048 0.381)
			(layers "B.Cu" "B.Mask" "B.Paste")
			(net "P0V8_SERDES_VDDA_PEX2")
		)
		(pad "2" smd rect
			(at -0.2667 0)
			(size 0.3048 0.381)
			(layers "B.Cu" "B.Mask" "B.Paste")
			(net "GND")
		)
	)
	(footprint ""
		(layer "B.Cu")
		(at 235.530644 -231.225598 -90)
		(property "Reference" "R4528"
			(at 0 0 90)
			(layer "B.SilkS")
			(hide yes)
			(effects
				(font
					(size 1.27 1.27)
				)
				(justify mirror)
			)
		)
		(property "Value" ""
			(at 0 0 90)
			(layer "B.Fab")
			(effects
				(font
					(size 1.27 1.27)
				)
				(justify mirror)
			)
		)
		(duplicate_pad_numbers_are_jumpers no)
		(fp_line
			(start -0.7874 0.4064)
			(end 0.7874 0.4064)
			(stroke
				(width 0.1524)
				(type default)
			)
			(layer "B.SilkS")
		)
		(fp_line
			(start 0.7874 0.4064)
			(end 0.7874 -0.4064)
			(stroke
				(width 0.1524)
				(type default)
			)
			(layer "B.SilkS")
		)
		(fp_line
			(start -0.7874 -0.4064)
			(end -0.7874 0.4064)
			(stroke
				(width 0.1524)
				(type default)
			)
			(layer "B.SilkS")
		)
		(fp_line
			(start 0.7874 -0.4064)
			(end -0.7874 -0.4064)
			(stroke
				(width 0.1524)
				(type default)
			)
			(layer "B.SilkS")
		)
		(fp_line
			(start -0.67945 0.3048)
			(end -0.120396 0.3048)
			(stroke
				(width 0.1)
				(type default)
			)
			(layer "B.Fab")
		)
		(fp_line
			(start -0.120396 0.3048)
			(end -0.120396 0.2794)
			(stroke
				(width 0.1)
				(type default)
			)
			(layer "B.Fab")
		)
		(fp_line
			(start 0.12065 0.3048)
			(end 0.67945 0.3048)
			(stroke
				(width 0.1)
				(type default)
			)
			(layer "B.Fab")
		)
		(fp_line
			(start 0.67945 0.3048)
			(end 0.67945 -0.305054)
			(stroke
				(width 0.1)
				(type default)
			)
			(layer "B.Fab")
		)
		(fp_line
			(start -0.120396 0.2794)
			(end 0.12065 0.2794)
			(stroke
				(width 0.1)
				(type default)
			)
			(layer "B.Fab")
		)
		(fp_line
			(start 0.12065 0.2794)
			(end 0.12065 0.3048)
			(stroke
				(width 0.1)
				(type default)
			)
			(layer "B.Fab")
		)
		(fp_line
			(start -0.12065 -0.2794)
			(end -0.12065 -0.3048)
			(stroke
				(width 0.1)
				(type default)
			)
			(layer "B.Fab")
		)
		(fp_line
			(start 0.12065 -0.2794)
			(end -0.12065 -0.2794)
			(stroke
				(width 0.1)
				(type default)
			)
			(layer "B.Fab")
		)
		(fp_line
			(start -0.67945 -0.3048)
			(end -0.67945 0.3048)
			(stroke
				(width 0.1)
				(type default)
			)
			(layer "B.Fab")
		)
		(fp_line
			(start -0.12065 -0.3048)
			(end -0.67945 -0.3048)
			(stroke
				(width 0.1)
				(type default)
			)
			(layer "B.Fab")
		)
		(fp_line
			(start 0.12065 -0.305054)
			(end 0.12065 -0.2794)
			(stroke
				(width 0.1)
				(type default)
			)
			(layer "B.Fab")
		)
		(fp_line
			(start 0.67945 -0.305054)
			(end 0.12065 -0.305054)
			(stroke
				(width 0.1)
				(type default)
			)
			(layer "B.Fab")
		)
		(pad "1" smd circle
			(at 0.40005 0 90)
			(size 0 0)
			(layers "B.Cu" "B.Mask" "B.Paste")
			(net "SSD14_PWRDIS_BIC")
		)
		(pad "2" smd circle
			(at -0.40005 0 90)
			(size 0 0)
			(layers "B.Cu" "B.Mask" "B.Paste")
			(net "SSD14_PWRDIS_BIC_R")
		)
	)
	(footprint ""
		(layer "B.Cu")
		(at 64.399922 -299.699934 -90)
		(property "Reference" "C1210"
			(at 0 0 90)
			(layer "B.SilkS")
			(hide yes)
			(effects
				(font
					(size 1.27 1.27)
				)
				(justify mirror)
			)
		)
		(property "Value" ""
			(at 0 0 90)
			(layer "B.Fab")
			(effects
				(font
					(size 1.27 1.27)
				)
				(justify mirror)
			)
		)
		(duplicate_pad_numbers_are_jumpers no)
		(fp_line
			(start -0.299974 0.150114)
			(end 0.299974 0.150114)
			(stroke
				(width 0.1)
				(type default)
			)
			(layer "B.Fab")
		)
		(fp_line
			(start 0.299974 0.150114)
			(end 0.299974 -0.150114)
			(stroke
				(width 0.1)
				(type default)
			)
			(layer "B.Fab")
		)
		(fp_line
			(start -0.299974 -0.150114)
			(end -0.299974 0.150114)
			(stroke
				(width 0.1)
				(type default)
			)
			(layer "B.Fab")
		)
		(fp_line
			(start 0.299974 -0.150114)
			(end -0.299974 -0.150114)
			(stroke
				(width 0.1)
				(type default)
			)
			(layer "B.Fab")
		)
		(pad "1" smd rect
			(at 0.2667 0 90)
			(size 0.3048 0.381)
			(layers "B.Cu" "B.Mask" "B.Paste")
			(net "P0V8_SERDES_VDDA_PEX0")
		)
		(pad "2" smd rect
			(at -0.2667 0 90)
			(size 0.3048 0.381)
			(layers "B.Cu" "B.Mask" "B.Paste")
			(net "GND")
		)
	)
	(footprint ""
		(layer "B.Cu")
		(at 130.016504 -325.30923 -90)
		(property "Reference" "C4273"
			(at 0 0 90)
			(layer "B.SilkS")
			(hide yes)
			(effects
				(font
					(size 1.27 1.27)
				)
				(justify mirror)
			)
		)
		(property "Value" ""
			(at 0 0 90)
			(layer "B.Fab")
			(effects
				(font
					(size 1.27 1.27)
				)
				(justify mirror)
			)
		)
		(duplicate_pad_numbers_are_jumpers no)
		(fp_line
			(start -1.2954 0.5842)
			(end 1.2954 0.5842)
			(stroke
				(width 0.1524)
				(type default)
			)
			(layer "B.SilkS")
		)
		(fp_line
			(start 1.2954 0.5842)
			(end 1.2954 -0.5842)
			(stroke
				(width 0.1524)
				(type default)
			)
			(layer "B.SilkS")
		)
		(fp_line
			(start -1.2954 -0.5842)
			(end -1.2954 0.5842)
			(stroke
				(width 0.1524)
				(type default)
			)
			(layer "B.SilkS")
		)
		(fp_line
			(start 1.2954 -0.5842)
			(end -1.2954 -0.5842)
			(stroke
				(width 0.1524)
				(type default)
			)
			(layer "B.SilkS")
		)
		(fp_line
			(start -0.8636 0.4572)
			(end 0.8636 0.4572)
			(stroke
				(width 0.1)
				(type default)
			)
			(layer "B.Fab")
		)
		(fp_line
			(start 0.8636 0.4572)
			(end 0.8636 0.4064)
			(stroke
				(width 0.1)
				(type default)
			)
			(layer "B.Fab")
		)
		(fp_line
			(start -1.1938 0.4064)
			(end -0.8636 0.4064)
			(stroke
				(width 0.1)
				(type default)
			)
			(layer "B.Fab")
		)
		(fp_line
			(start -0.8636 0.4064)
			(end -0.8636 0.4572)
			(stroke
				(width 0.1)
				(type default)
			)
			(layer "B.Fab")
		)
		(fp_line
			(start 0.8636 0.4064)
			(end 1.1938 0.4064)
			(stroke
				(width 0.1)
				(type default)
			)
			(layer "B.Fab")
		)
		(fp_line
			(start 1.1938 0.4064)
			(end 1.1938 -0.4064)
			(stroke
				(width 0.1)
				(type default)
			)
			(layer "B.Fab")
		)
		(fp_line
			(start -1.1938 -0.4064)
			(end -1.1938 0.4064)
			(stroke
				(width 0.1)
				(type default)
			)
			(layer "B.Fab")
		)
		(fp_line
			(start -0.8636 -0.4064)
			(end -1.1938 -0.4064)
			(stroke
				(width 0.1)
				(type default)
			)
			(layer "B.Fab")
		)
		(fp_line
			(start 0.8636 -0.4064)
			(end 0.8636 -0.4572)
			(stroke
				(width 0.1)
				(type default)
			)
			(layer "B.Fab")
		)
		(fp_line
			(start 1.1938 -0.4064)
			(end 0.8636 -0.4064)
			(stroke
				(width 0.1)
				(type default)
			)
			(layer "B.Fab")
		)
		(fp_line
			(start -0.8636 -0.4572)
			(end -0.8636 -0.4064)
			(stroke
				(width 0.1)
				(type default)
			)
			(layer "B.Fab")
		)
		(fp_line
			(start 0.8636 -0.4572)
			(end -0.8636 -0.4572)
			(stroke
				(width 0.1)
				(type default)
			)
			(layer "B.Fab")
		)
		(pad "1" smd rect
			(at 0.7366 0 180)
			(size 0.7112 0.8128)
			(layers "B.Cu" "B.Mask" "B.Paste")
			(net "P0V8_SERDES_VDDA_PEX1_C11")
		)
		(pad "2" smd rect
			(at -0.7366 0 180)
			(size 0.7112 0.8128)
			(layers "B.Cu" "B.Mask" "B.Paste")
			(net "GND")
		)
	)
	(footprint ""
		(layer "B.Cu")
		(at 231.889046 -148.047202)
		(property "Reference" "C2787"
			(at 0 0 0)
			(layer "B.SilkS")
			(hide yes)
			(effects
				(font
					(size 1.27 1.27)
				)
				(justify mirror)
			)
		)
		(property "Value" ""
			(at 0 0 0)
			(layer "B.Fab")
			(effects
				(font
					(size 1.27 1.27)
				)
				(justify mirror)
			)
		)
		(duplicate_pad_numbers_are_jumpers no)
		(fp_line
			(start -0.7874 -0.4064)
			(end -0.7874 0.4064)
			(stroke
				(width 0.1524)
				(type default)
			)
			(layer "B.SilkS")
		)
		(fp_line
			(start -0.7874 0.4064)
			(end 0.7874 0.4064)
			(stroke
				(width 0.1524)
				(type default)
			)
			(layer "B.SilkS")
		)
		(fp_line
			(start 0.7874 -0.4064)
			(end -0.7874 -0.4064)
			(stroke
				(width 0.1524)
				(type default)
			)
			(layer "B.SilkS")
		)
		(fp_line
			(start 0.7874 0.4064)
			(end 0.7874 -0.4064)
			(stroke
				(width 0.1524)
				(type default)
			)
			(layer "B.SilkS")
		)
		(fp_line
			(start -0.67945 -0.3048)
			(end -0.67945 0.3048)
			(stroke
				(width 0.1)
				(type default)
			)
			(layer "B.Fab")
		)
		(fp_line
			(start -0.67945 0.3048)
			(end -0.120396 0.3048)
			(stroke
				(width 0.1)
				(type default)
			)
			(layer "B.Fab")
		)
		(fp_line
			(start -0.12065 -0.3048)
			(end -0.67945 -0.3048)
			(stroke
				(width 0.1)
				(type default)
			)
			(layer "B.Fab")
		)
		(fp_line
			(start -0.12065 -0.2794)
			(end -0.12065 -0.3048)
			(stroke
				(width 0.1)
				(type default)
			)
			(layer "B.Fab")
		)
		(fp_line
			(start -0.120396 0.2794)
			(end 0.12065 0.2794)
			(stroke
				(width 0.1)
				(type default)
			)
			(layer "B.Fab")
		)
		(fp_line
			(start -0.120396 0.3048)
			(end -0.120396 0.2794)
			(stroke
				(width 0.1)
				(type default)
			)
			(layer "B.Fab")
		)
		(fp_line
			(start 0.12065 -0.305054)
			(end 0.12065 -0.2794)
			(stroke
				(width 0.1)
				(type default)
			)
			(layer "B.Fab")
		)
		(fp_line
			(start 0.12065 -0.2794)
			(end -0.12065 -0.2794)
			(stroke
				(width 0.1)
				(type default)
			)
			(layer "B.Fab")
		)
		(fp_line
			(start 0.12065 0.2794)
			(end 0.12065 0.3048)
			(stroke
				(width 0.1)
				(type default)
			)
			(layer "B.Fab")
		)
		(fp_line
			(start 0.12065 0.3048)
			(end 0.67945 0.3048)
			(stroke
				(width 0.1)
				(type default)
			)
			(layer "B.Fab")
		)
		(fp_line
			(start 0.67945 -0.305054)
			(end 0.12065 -0.305054)
			(stroke
				(width 0.1)
				(type default)
			)
			(layer "B.Fab")
		)
		(fp_line
			(start 0.67945 0.3048)
			(end 0.67945 -0.305054)
			(stroke
				(width 0.1)
				(type default)
			)
			(layer "B.Fab")
		)
		(pad "1" smd circle
			(at 0.40005 0 180)
			(size 0 0)
			(layers "B.Cu" "B.Mask" "B.Paste")
			(net "P3V3_CLK_GEN_VDD_CK440_PEX")
		)
		(pad "2" smd circle
			(at -0.40005 0 180)
			(size 0 0)
			(layers "B.Cu" "B.Mask" "B.Paste")
			(net "GND")
		)
	)
	(footprint ""
		(layer "B.Cu")
		(at 253.97968 -85.586316)
		(property "Reference" "C2650"
			(at 0 0 0)
			(layer "B.SilkS")
			(hide yes)
			(effects
				(font
					(size 1.27 1.27)
				)
				(justify mirror)
			)
		)
		(property "Value" ""
			(at 0 0 0)
			(layer "B.Fab")
			(effects
				(font
					(size 1.27 1.27)
				)
				(justify mirror)
			)
		)
		(duplicate_pad_numbers_are_jumpers no)
		(fp_line
			(start -1.2954 -0.5842)
			(end -1.2954 0.5842)
			(stroke
				(width 0.1524)
				(type default)
			)
			(layer "B.SilkS")
		)
		(fp_line
			(start -1.2954 0.5842)
			(end 1.2954 0.5842)
			(stroke
				(width 0.1524)
				(type default)
			)
			(layer "B.SilkS")
		)
		(fp_line
			(start 1.2954 -0.5842)
			(end -1.2954 -0.5842)
			(stroke
				(width 0.1524)
				(type default)
			)
			(layer "B.SilkS")
		)
		(fp_line
			(start 1.2954 0.5842)
			(end 1.2954 -0.5842)
			(stroke
				(width 0.1524)
				(type default)
			)
			(layer "B.SilkS")
		)
		(fp_line
			(start -1.1938 -0.4064)
			(end -1.1938 0.4064)
			(stroke
				(width 0.1)
				(type default)
			)
			(layer "B.Fab")
		)
		(fp_line
			(start -1.1938 0.4064)
			(end -0.8636 0.4064)
			(stroke
				(width 0.1)
				(type default)
			)
			(layer "B.Fab")
		)
		(fp_line
			(start -0.8636 -0.4572)
			(end -0.8636 -0.4064)
			(stroke
				(width 0.1)
				(type default)
			)
			(layer "B.Fab")
		)
		(fp_line
			(start -0.8636 -0.4064)
			(end -1.1938 -0.4064)
			(stroke
				(width 0.1)
				(type default)
			)
			(layer "B.Fab")
		)
		(fp_line
			(start -0.8636 0.4064)
			(end -0.8636 0.4572)
			(stroke
				(width 0.1)
				(type default)
			)
			(layer "B.Fab")
		)
		(fp_line
			(start -0.8636 0.4572)
			(end 0.8636 0.4572)
			(stroke
				(width 0.1)
				(type default)
			)
			(layer "B.Fab")
		)
		(fp_line
			(start 0.8636 -0.4572)
			(end -0.8636 -0.4572)
			(stroke
				(width 0.1)
				(type default)
			)
			(layer "B.Fab")
		)
		(fp_line
			(start 0.8636 -0.4064)
			(end 0.8636 -0.4572)
			(stroke
				(width 0.1)
				(type default)
			)
			(layer "B.Fab")
		)
		(fp_line
			(start 0.8636 0.4064)
			(end 1.1938 0.4064)
			(stroke
				(width 0.1)
				(type default)
			)
			(layer "B.Fab")
		)
		(fp_line
			(start 0.8636 0.4572)
			(end 0.8636 0.4064)
			(stroke
				(width 0.1)
				(type default)
			)
			(layer "B.Fab")
		)
		(fp_line
			(start 1.1938 -0.4064)
			(end 0.8636 -0.4064)
			(stroke
				(width 0.1)
				(type default)
			)
			(layer "B.Fab")
		)
		(fp_line
			(start 1.1938 0.4064)
			(end 1.1938 -0.4064)
			(stroke
				(width 0.1)
				(type default)
			)
			(layer "B.Fab")
		)
		(pad "1" smd rect
			(at 0.7366 0 270)
			(size 0.7112 0.8128)
			(layers "B.Cu" "B.Mask" "B.Paste")
			(net "P3V3_CLK_GEN_VDDPT_CK440")
		)
		(pad "2" smd rect
			(at -0.7366 0 270)
			(size 0.7112 0.8128)
			(layers "B.Cu" "B.Mask" "B.Paste")
			(net "GND")
		)
	)
)
